(kicad_pcb
	(version 20260206)
	(generator "pcbnew")
	(generator_version "10.0")
	(general
		(thickness 1.6)
		(legacy_teardrops no)
	)
	(paper "A4")
	(title_block
		(title "panther-plus-userver — 13130-1b_20150205.brd")
		(comment 1 "Honey Badger (Wiwynn) / footprint 282 of 1509 (U13), pads 820-937 of 1283")
	)
	(layers
		(0 "F.Cu" signal "TOP")
		(4 "In1.Cu" signal "L2")
		(6 "In2.Cu" signal "L3")
		(8 "In3.Cu" signal "L4")
		(10 "In4.Cu" signal "L5")
		(12 "In5.Cu" signal "L6")
		(14 "In6.Cu" signal "L7")
		(16 "In7.Cu" signal "L8")
		(18 "In8.Cu" signal "L9")
		(20 "In9.Cu" signal "L10")
		(22 "In10.Cu" signal "L11")
		(2 "B.Cu" signal "BOTTOM")
		(9 "F.Adhes" user "F.Adhesive")
		(11 "B.Adhes" user "B.Adhesive")
		(13 "F.Paste" user "Package Geometry/Pastemask Top")
		(15 "B.Paste" user "Package Geometry/Pastemask Bottom")
		(5 "F.SilkS" user "Ref Des/Silkscreen Top")
		(7 "B.SilkS" user "Ref Des/Silkscreen Bottom")
		(1 "F.Mask" user "Board Geometry/Soldermask Top")
		(3 "B.Mask" user "Board Geometry/Soldermask Bottom")
		(17 "Dwgs.User" user "User.Drawings")
		(19 "Cmts.User" user "User.Comments")
		(21 "Eco1.User" user "User.Eco1")
		(23 "Eco2.User" user "User.Eco2")
		(25 "Edge.Cuts" user "Board Geometry/Outline")
		(27 "Margin" user)
		(31 "F.CrtYd" user "Package Geometry/Place Bound Top")
		(29 "B.CrtYd" user "Package Geometry/Place Bound Bottom")
		(35 "F.Fab" user "Ref Des/Assembly Top")
		(33 "B.Fab" user "Ref Des/Assembly Bottom")
	)
	(footprint ""
		(layer "F.Cu")
		(at 95.849948 -39.200074 180)
		(property "Reference" "U13"
			(at 0 0 180)
			(layer "F.SilkS")
			(hide yes)
			(effects
				(font
					(size 1.27 1.27)
				)
			)
		)
		(property "Value" "AVOTON-GP"
			(at -25.0317 -2.4892 180)
			(unlocked yes)
			(layer "F.Fab")
			(hide yes)
			(effects
				(font
					(size 1.016 1.016)
					(thickness 0.1524)
				)
			)
		)
		(property "Device Type" "BGA1283M3428-3H197"
			(at -25.0317 -4.0132 180)
			(unlocked yes)
			(layer "F.Fab")
			(hide yes)
			(effects
				(font
					(size 1.016 1.016)
					(thickness 0.1524)
				)
			)
		)
		(duplicate_pad_numbers_are_jumpers no)
		(pad "BN44" smd circle
			(at 5.36448 12.80668 180)
			(size 0.3048 0.3048)
			(layers "F.Cu" "F.Mask" "F.Paste")
			(net "P2E_CPU_ETH10G_C_TX_DP11")
		)
		(pad "BN46" smd circle
			(at 6.39572 12.64158 180)
			(size 0.3048 0.3048)
			(layers "F.Cu" "F.Mask" "F.Paste")
			(net "P2E_CPU_ETH10G_C_TX_DP10")
		)
		(pad "BN48" smd circle
			(at 7.32028 12.63904 180)
			(size 0.3048 0.3048)
			(layers "F.Cu" "F.Mask" "F.Paste")
			(net "P2E_CPU_ETH10G_C_TX_DP9")
		)
		(pad "BN50" smd circle
			(at 8.38708 12.75334 180)
			(size 0.3048 0.3048)
			(layers "F.Cu" "F.Mask" "F.Paste")
			(net "P2E_CPU_SAS_C_TX_DP7")
		)
		(pad "BN53" smd circle
			(at 9.8679 12.80668 180)
			(size 0.3048 0.3048)
			(layers "F.Cu" "F.Mask" "F.Paste")
			(net "P2E_CPU_SAS_C_TX_DP5")
		)
		(pad "BN55" smd circle
			(at 10.8966 12.64158 180)
			(size 0.3048 0.3048)
			(layers "F.Cu" "F.Mask" "F.Paste")
			(net "P2E_CPU_SAS_C_TX_DN3")
		)
		(pad "BN57" smd circle
			(at 11.8237 12.63904 180)
			(size 0.3048 0.3048)
			(layers "F.Cu" "F.Mask" "F.Paste")
			(net "P2E_CPU_SAS_C_TX_DN2")
		)
		(pad "BP1" smd circle
			(at -16.11122 13.11148 180)
			(size 0.5588 0.5588)
			(layers "F.Cu" "F.Mask" "F.Paste")
			(net "GND")
		)
		(pad "BP3" smd circle
			(at -15.29842 13.11148 180)
			(size 0.5588 0.5588)
			(layers "F.Cu" "F.Mask" "F.Paste")
			(net "GND")
		)
		(pad "BP5" smd circle
			(at -14.48562 13.11148 180)
			(size 0.4064 0.4064)
			(layers "F.Cu" "F.Mask" "F.Paste")
			(net "GND")
		)
		(pad "BP6" smd circle
			(at -13.67282 13.11148 180)
			(size 0.4064 0.4064)
			(layers "F.Cu" "F.Mask" "F.Paste")
			(net "M_A_MON1_N")
		)
		(pad "BP8" smd circle
			(at -12.86002 13.11148 180)
			(size 0.4064 0.4064)
			(layers "F.Cu" "F.Mask" "F.Paste")
			(net "M_A_MON1_P")
		)
		(pad "BP10" smd oval
			(at -11.96594 13.24864 180)
			(size 0.254 0.3429)
			(layers "F.Cu" "F.Mask" "F.Paste")
			(net "GND")
		)
		(pad "BP13" smd oval
			(at -10.34034 13.24864 180)
			(size 0.254 0.3429)
			(layers "F.Cu" "F.Mask" "F.Paste")
			(net "GND")
		)
		(pad "BP16" smd oval
			(at -8.9027 13.24864 180)
			(size 0.254 0.3429)
			(layers "F.Cu" "F.Mask" "F.Paste")
			(net "M_A_DQ45")
		)
		(pad "BP19" smd oval
			(at -7.46252 13.24864 180)
			(size 0.254 0.3429)
			(layers "F.Cu" "F.Mask" "F.Paste")
			(net "M_A_DQ46")
		)
		(pad "BP22" smd oval
			(at -5.83692 13.24864 180)
			(size 0.254 0.3429)
			(layers "F.Cu" "F.Mask" "F.Paste")
			(net "GND")
		)
		(pad "BP25" smd oval
			(at -4.39928 13.24864 180)
			(size 0.254 0.3429)
			(layers "F.Cu" "F.Mask" "F.Paste")
			(net "M_A_DQ49")
		)
		(pad "BP28" smd oval
			(at -2.96164 13.24864 180)
			(size 0.254 0.3429)
			(layers "F.Cu" "F.Mask" "F.Paste")
			(net "M_A_DQ55")
		)
		(pad "BP31" smd oval
			(at -1.33604 13.24864 180)
			(size 0.254 0.3429)
			(layers "F.Cu" "F.Mask" "F.Paste")
			(net "GND")
		)
		(pad "BP34" smd oval
			(at 0.10414 13.24864 180)
			(size 0.254 0.3429)
			(layers "F.Cu" "F.Mask" "F.Paste")
			(net "M_A_DQS_DP7")
		)
		(pad "BP37" smd oval
			(at 1.54178 13.24864 180)
			(size 0.254 0.3429)
			(layers "F.Cu" "F.Mask" "F.Paste")
			(net "GND")
		)
		(pad "BP40" smd oval
			(at 3.16738 13.24864 180)
			(size 0.254 0.3429)
			(layers "F.Cu" "F.Mask" "F.Paste")
			(net "GND")
		)
		(pad "BP43" smd oval
			(at 4.60756 13.24864 180)
			(size 0.254 0.3429)
			(layers "F.Cu" "F.Mask" "F.Paste")
			(net "P2E_CPU_NGFF_C_TX_DP12")
		)
		(pad "BP46" smd oval
			(at 6.0452 13.24864 180)
			(size 0.254 0.3429)
			(layers "F.Cu" "F.Mask" "F.Paste")
			(net "GND")
		)
		(pad "BP49" smd oval
			(at 7.6708 13.24864 180)
			(size 0.254 0.3429)
			(layers "F.Cu" "F.Mask" "F.Paste")
			(net "P2E_CPU_ETH10G_C_TX_DP8")
		)
		(pad "BP52" smd oval
			(at 9.10844 13.24864 180)
			(size 0.254 0.3429)
			(layers "F.Cu" "F.Mask" "F.Paste")
			(net "GND")
		)
		(pad "BP55" smd oval
			(at 10.54862 13.24864 180)
			(size 0.254 0.3429)
			(layers "F.Cu" "F.Mask" "F.Paste")
			(net "GND")
		)
		(pad "BP58" smd oval
			(at 12.17422 13.24864 180)
			(size 0.254 0.3429)
			(layers "F.Cu" "F.Mask" "F.Paste")
			(net "GND")
		)
		(pad "BP59" smd circle
			(at 12.86002 13.11148 180)
			(size 0.4064 0.4064)
			(layers "F.Cu" "F.Mask" "F.Paste")
			(net "GND")
		)
		(pad "BP61" smd circle
			(at 13.67282 13.11148 180)
			(size 0.4064 0.4064)
			(layers "F.Cu" "F.Mask" "F.Paste")
			(net "GND")
		)
		(pad "BP62" smd circle
			(at 14.48562 13.11148 180)
			(size 0.4064 0.4064)
			(layers "F.Cu" "F.Mask" "F.Paste")
			(net "GND")
		)
		(pad "BP64" smd circle
			(at 15.29842 13.11148 180)
			(size 0.5588 0.5588)
			(layers "F.Cu" "F.Mask" "F.Paste")
			(net "GND")
		)
		(pad "BP66" smd circle
			(at 16.11122 13.11148 180)
			(size 0.5588 0.5588)
			(layers "F.Cu" "F.Mask" "F.Paste")
			(net "GND")
		)
		(pad "C3" smd circle
			(at -15.29842 -12.29868 180)
			(size 0.5588 0.5588)
			(layers "F.Cu" "F.Mask" "F.Paste")
			(net "GND")
		)
		(pad "C5" smd circle
			(at -14.48562 -12.29868 180)
			(size 0.4064 0.4064)
			(layers "F.Cu" "F.Mask" "F.Paste")
			(net "M_B_MON1_N")
		)
		(pad "C6" smd circle
			(at -13.61186 -12.30376 180)
			(size 0.3048 0.3048)
			(layers "F.Cu" "F.Mask" "F.Paste")
			(net "GND")
		)
		(pad "C9" smd circle
			(at -12.40282 -12.2428 180)
			(size 0.3048 0.3048)
			(layers "F.Cu" "F.Mask" "F.Paste")
			(net "M_B_CK_DP0")
		)
		(pad "C13" smd circle
			(at -10.29208 -12.24788 180)
			(size 0.3048 0.3048)
			(layers "F.Cu" "F.Mask" "F.Paste")
			(net "M_B_ECC6")
		)
		(pad "C15" smd circle
			(at -9.05764 -12.30376 180)
			(size 0.3048 0.3048)
			(layers "F.Cu" "F.Mask" "F.Paste")
			(net "M_B_ECC1")
		)
		(pad "C18" smd circle
			(at -7.90194 -12.2428 180)
			(size 0.3048 0.3048)
			(layers "F.Cu" "F.Mask" "F.Paste")
			(net "GND")
		)
		(pad "C22" smd circle
			(at -5.78866 -12.24788 180)
			(size 0.3048 0.3048)
			(layers "F.Cu" "F.Mask" "F.Paste")
			(net "M_B_DQS_DN2")
		)
		(pad "C24" smd circle
			(at -4.55676 -12.30376 180)
			(size 0.3048 0.3048)
			(layers "F.Cu" "F.Mask" "F.Paste")
			(net "M_B_DQ20")
		)
		(pad "C27" smd circle
			(at -3.39852 -12.2428 180)
			(size 0.3048 0.3048)
			(layers "F.Cu" "F.Mask" "F.Paste")
			(net "M_B_DQ11")
		)
		(pad "C31" smd circle
			(at -1.28524 -12.24788 180)
			(size 0.3048 0.3048)
			(layers "F.Cu" "F.Mask" "F.Paste")
			(net "M_B_DQ9")
		)
		(pad "C33" smd circle
			(at -0.05334 -12.30376 180)
			(size 0.3048 0.3048)
			(layers "F.Cu" "F.Mask" "F.Paste")
			(net "GND")
		)
		(pad "C36" smd circle
			(at 1.1049 -12.2428 180)
			(size 0.3048 0.3048)
			(layers "F.Cu" "F.Mask" "F.Paste")
			(net "M_B_DQ7")
		)
		(pad "C40" smd circle
			(at 3.21564 -12.24788 180)
			(size 0.3048 0.3048)
			(layers "F.Cu" "F.Mask" "F.Paste")
			(net "M_B_DQ5")
		)
		(pad "C42" smd circle
			(at 4.45008 -12.30376 180)
			(size 0.3048 0.3048)
			(layers "F.Cu" "F.Mask" "F.Paste")
			(net "Net_1364")
		)
		(pad "C45" smd circle
			(at 5.60832 -12.2428 180)
			(size 0.3048 0.3048)
			(layers "F.Cu" "F.Mask" "F.Paste")
			(net "GND")
		)
		(pad "C49" smd circle
			(at 7.71906 -12.24788 180)
			(size 0.3048 0.3048)
			(layers "F.Cu" "F.Mask" "F.Paste")
			(net "GND")
		)
		(pad "C51" smd circle
			(at 8.9535 -12.30376 180)
			(size 0.3048 0.3048)
			(layers "F.Cu" "F.Mask" "F.Paste")
			(net "GND")
		)
		(pad "C54" smd circle
			(at 10.11174 -12.2428 180)
			(size 0.3048 0.3048)
			(layers "F.Cu" "F.Mask" "F.Paste")
			(net "Net_1351")
		)
		(pad "C58" smd circle
			(at 12.22248 -12.24788 180)
			(size 0.3048 0.3048)
			(layers "F.Cu" "F.Mask" "F.Paste")
			(net "GND")
		)
		(pad "C60" smd circle
			(at 13.40612 -12.30376 180)
			(size 0.3048 0.3048)
			(layers "F.Cu" "F.Mask" "F.Paste")
			(net "Net_1358")
		)
		(pad "C62" smd circle
			(at 14.48562 -12.29868 180)
			(size 0.4064 0.4064)
			(layers "F.Cu" "F.Mask" "F.Paste")
			(net "Net_1357")
		)
		(pad "C64" smd circle
			(at 15.29842 -12.29868 180)
			(size 0.4064 0.4064)
			(layers "F.Cu" "F.Mask" "F.Paste")
			(net "GND")
		)
		(pad "C66" smd circle
			(at 16.11122 -12.29868 180)
			(size 0.5588 0.5588)
			(layers "F.Cu" "F.Mask" "F.Paste")
			(net "GND")
		)
		(pad "D6" smd circle
			(at -13.61186 -11.54176 180)
			(size 0.3048 0.3048)
			(layers "F.Cu" "F.Mask" "F.Paste")
			(net "GND")
		)
		(pad "D8" smd circle
			(at -12.93368 -11.75258 180)
			(size 0.3048 0.3048)
			(layers "F.Cu" "F.Mask" "F.Paste")
			(net "M_B_CK_DN0")
		)
		(pad "D10" smd circle
			(at -11.79322 -11.8999 180)
			(size 0.3048 0.3048)
			(layers "F.Cu" "F.Mask" "F.Paste")
			(net "GND")
		)
		(pad "D12" smd circle
			(at -10.90422 -11.8999 180)
			(size 0.3048 0.3048)
			(layers "F.Cu" "F.Mask" "F.Paste")
			(net "M_B_ECC2")
		)
		(pad "D14" smd circle
			(at -9.78916 -11.75258 180)
			(size 0.3048 0.3048)
			(layers "F.Cu" "F.Mask" "F.Paste")
			(net "M_B_DQS_DN8")
		)
		(pad "D15" smd circle
			(at -9.10844 -11.54176 180)
			(size 0.3048 0.3048)
			(layers "F.Cu" "F.Mask" "F.Paste")
			(net "M_B_ECC0")
		)
		(pad "D17" smd circle
			(at -8.44042 -11.79576 180)
			(size 0.3048 0.3048)
			(layers "F.Cu" "F.Mask" "F.Paste")
			(net "M_B_ECC4")
		)
		(pad "D19" smd circle
			(at -7.2898 -11.8999 180)
			(size 0.3048 0.3048)
			(layers "F.Cu" "F.Mask" "F.Paste")
			(net "M_B_DQ18")
		)
		(pad "D21" smd circle
			(at -6.4008 -11.8999 180)
			(size 0.3048 0.3048)
			(layers "F.Cu" "F.Mask" "F.Paste")
			(net "M_B_DQ23")
		)
		(pad "D23" smd circle
			(at -5.28574 -11.75258 180)
			(size 0.3048 0.3048)
			(layers "F.Cu" "F.Mask" "F.Paste")
			(net "M_B_DQ16")
		)
		(pad "D24" smd circle
			(at -4.60756 -11.54176 180)
			(size 0.3048 0.3048)
			(layers "F.Cu" "F.Mask" "F.Paste")
			(net "M_B_DQ21")
		)
		(pad "D26" smd circle
			(at -3.937 -11.79576 180)
			(size 0.3048 0.3048)
			(layers "F.Cu" "F.Mask" "F.Paste")
			(net "GND")
		)
		(pad "D28" smd circle
			(at -2.78638 -11.8999 180)
			(size 0.3048 0.3048)
			(layers "F.Cu" "F.Mask" "F.Paste")
			(net "M_B_DQ14")
		)
		(pad "D30" smd circle
			(at -1.89738 -11.8999 180)
			(size 0.3048 0.3048)
			(layers "F.Cu" "F.Mask" "F.Paste")
			(net "M_B_DQS_DP1")
		)
		(pad "D32" smd circle
			(at -0.78232 -11.75258 180)
			(size 0.3048 0.3048)
			(layers "F.Cu" "F.Mask" "F.Paste")
			(net "M_B_DQ13")
		)
		(pad "D33" smd circle
			(at -0.10414 -11.54176 180)
			(size 0.3048 0.3048)
			(layers "F.Cu" "F.Mask" "F.Paste")
			(net "GND")
		)
		(pad "D35" smd circle
			(at 0.56388 -11.79576 180)
			(size 0.3048 0.3048)
			(layers "F.Cu" "F.Mask" "F.Paste")
			(net "M_B_DQ3")
		)
		(pad "D37" smd circle
			(at 1.71704 -11.8999 180)
			(size 0.3048 0.3048)
			(layers "F.Cu" "F.Mask" "F.Paste")
			(net "M_B_DQS_DP0")
		)
		(pad "D39" smd circle
			(at 2.60604 -11.8999 180)
			(size 0.3048 0.3048)
			(layers "F.Cu" "F.Mask" "F.Paste")
			(net "M_B_DQ1")
		)
		(pad "D41" smd circle
			(at 3.71856 -11.75258 180)
			(size 0.3048 0.3048)
			(layers "F.Cu" "F.Mask" "F.Paste")
			(net "GND")
		)
		(pad "D42" smd circle
			(at 4.39928 -11.54176 180)
			(size 0.3048 0.3048)
			(layers "F.Cu" "F.Mask" "F.Paste")
			(net "GND")
		)
		(pad "D44" smd circle
			(at 5.0673 -11.79576 180)
			(size 0.3048 0.3048)
			(layers "F.Cu" "F.Mask" "F.Paste")
			(net "Net_1362")
		)
		(pad "D46" smd circle
			(at 6.21792 -11.8999 180)
			(size 0.3048 0.3048)
			(layers "F.Cu" "F.Mask" "F.Paste")
			(net "Net_278")
		)
		(pad "D48" smd circle
			(at 7.10692 -11.8999 180)
			(size 0.3048 0.3048)
			(layers "F.Cu" "F.Mask" "F.Paste")
			(net "CPU_GBE_TX_DP0")
		)
		(pad "D50" smd circle
			(at 8.22198 -11.75258 180)
			(size 0.3048 0.3048)
			(layers "F.Cu" "F.Mask" "F.Paste")
			(net "CLK_100M_CPU_GBE_DN")
		)
		(pad "D51" smd circle
			(at 8.9027 -11.54176 180)
			(size 0.3048 0.3048)
			(layers "F.Cu" "F.Mask" "F.Paste")
			(net "GND")
		)
		(pad "D53" smd circle
			(at 9.57072 -11.79576 180)
			(size 0.3048 0.3048)
			(layers "F.Cu" "F.Mask" "F.Paste")
			(net "Net_1350")
		)
		(pad "D55" smd circle
			(at 10.72134 -11.8999 180)
			(size 0.3048 0.3048)
			(layers "F.Cu" "F.Mask" "F.Paste")
			(net "GND")
		)
		(pad "D57" smd circle
			(at 11.61034 -11.8999 180)
			(size 0.3048 0.3048)
			(layers "F.Cu" "F.Mask" "F.Paste")
			(net "SATA2_TX_DN0")
		)
		(pad "D59" smd circle
			(at 12.7254 -11.75258 180)
			(size 0.3048 0.3048)
			(layers "F.Cu" "F.Mask" "F.Paste")
			(net "GND")
		)
		(pad "D60" smd circle
			(at 13.40612 -11.54176 180)
			(size 0.3048 0.3048)
			(layers "F.Cu" "F.Mask" "F.Paste")
			(net "Net_1354")
		)
		(pad "E1" smd circle
			(at -16.11122 -11.48588 180)
			(size 0.5588 0.5588)
			(layers "F.Cu" "F.Mask" "F.Paste")
			(net "GND")
		)
		(pad "E3" smd circle
			(at -15.29842 -11.48588 180)
			(size 0.4064 0.4064)
			(layers "F.Cu" "F.Mask" "F.Paste")
			(net "GND")
		)
		(pad "E5" smd circle
			(at -14.48562 -11.48588 180)
			(size 0.4064 0.4064)
			(layers "F.Cu" "F.Mask" "F.Paste")
			(net "M_B_MON1_P")
		)
		(pad "E7" smd circle
			(at -13.10132 -11.06424 180)
			(size 0.3048 0.3048)
			(layers "F.Cu" "F.Mask" "F.Paste")
			(net "PV_VDDR")
		)
		(pad "E9" smd circle
			(at -12.3952 -11.07948 180)
			(size 0.3048 0.3048)
			(layers "F.Cu" "F.Mask" "F.Paste")
			(net "PV_VDDR")
		)
		(pad "E10" smd circle
			(at -11.69924 -11.20394 180)
			(size 0.3048 0.3048)
			(layers "F.Cu" "F.Mask" "F.Paste")
			(net "GND")
		)
		(pad "E12" smd circle
			(at -11.00074 -11.20394 180)
			(size 0.3048 0.3048)
			(layers "F.Cu" "F.Mask" "F.Paste")
			(net "M_B_ECC3")
		)
		(pad "E13" smd circle
			(at -10.32256 -11.01344 180)
			(size 0.3048 0.3048)
			(layers "F.Cu" "F.Mask" "F.Paste")
			(net "GND")
		)
		(pad "E14" smd circle
			(at -9.61898 -11.06424 180)
			(size 0.3048 0.3048)
			(layers "F.Cu" "F.Mask" "F.Paste")
			(net "GND")
		)
		(pad "E16" smd circle
			(at -8.5979 -11.06424 180)
			(size 0.3048 0.3048)
			(layers "F.Cu" "F.Mask" "F.Paste")
			(net "GND")
		)
		(pad "E18" smd circle
			(at -7.89178 -11.07948 180)
			(size 0.3048 0.3048)
			(layers "F.Cu" "F.Mask" "F.Paste")
			(net "GND")
		)
		(pad "E19" smd circle
			(at -7.19836 -11.20394 180)
			(size 0.3048 0.3048)
			(layers "F.Cu" "F.Mask" "F.Paste")
			(net "GND")
		)
		(pad "E21" smd circle
			(at -6.49732 -11.20394 180)
			(size 0.3048 0.3048)
			(layers "F.Cu" "F.Mask" "F.Paste")
			(net "GND")
		)
		(pad "E22" smd circle
			(at -5.81914 -11.01344 180)
			(size 0.3048 0.3048)
			(layers "F.Cu" "F.Mask" "F.Paste")
			(net "GND")
		)
		(pad "E23" smd circle
			(at -5.1181 -11.06424 180)
			(size 0.3048 0.3048)
			(layers "F.Cu" "F.Mask" "F.Paste")
			(net "GND")
		)
		(pad "E25" smd circle
			(at -4.09448 -11.06424 180)
			(size 0.3048 0.3048)
			(layers "F.Cu" "F.Mask" "F.Paste")
			(net "GND")
		)
		(pad "E27" smd circle
			(at -3.38836 -11.07948 180)
			(size 0.3048 0.3048)
			(layers "F.Cu" "F.Mask" "F.Paste")
			(net "GND")
		)
		(pad "E28" smd circle
			(at -2.69494 -11.20394 180)
			(size 0.3048 0.3048)
			(layers "F.Cu" "F.Mask" "F.Paste")
			(net "GND")
		)
		(pad "E30" smd circle
			(at -1.9939 -11.20394 180)
			(size 0.3048 0.3048)
			(layers "F.Cu" "F.Mask" "F.Paste")
			(net "GND")
		)
		(pad "E31" smd circle
			(at -1.31572 -11.01344 180)
			(size 0.3048 0.3048)
			(layers "F.Cu" "F.Mask" "F.Paste")
			(net "GND")
		)
		(pad "E32" smd circle
			(at -0.61468 -11.06424 180)
			(size 0.3048 0.3048)
			(layers "F.Cu" "F.Mask" "F.Paste")
			(net "M_B_DQ12")
		)
		(pad "E34" smd circle
			(at 0.4064 -11.06424 180)
			(size 0.3048 0.3048)
			(layers "F.Cu" "F.Mask" "F.Paste")
			(net "GND")
		)
		(pad "E36" smd circle
			(at 1.11506 -11.0744 180)
			(size 0.3048 0.3048)
			(layers "F.Cu" "F.Mask" "F.Paste")
			(net "GND")
		)
		(pad "E37" smd circle
			(at 1.80848 -11.20394 180)
			(size 0.3048 0.3048)
			(layers "F.Cu" "F.Mask" "F.Paste")
			(net "GND")
		)
		(pad "E39" smd circle
			(at 2.50952 -11.20394 180)
			(size 0.3048 0.3048)
			(layers "F.Cu" "F.Mask" "F.Paste")
			(net "GND")
		)
		(pad "E40" smd circle
			(at 3.18516 -11.01344 180)
			(size 0.3048 0.3048)
			(layers "F.Cu" "F.Mask" "F.Paste")
			(net "GND")
		)
		(pad "E41" smd circle
			(at 3.88874 -11.06424 180)
			(size 0.3048 0.3048)
			(layers "F.Cu" "F.Mask" "F.Paste")
			(net "GND")
		)
		(pad "E43" smd circle
			(at 4.90982 -11.06424 180)
			(size 0.3048 0.3048)
			(layers "F.Cu" "F.Mask" "F.Paste")
			(net "GND")
		)
		(pad "E45" smd circle
			(at 5.61848 -11.07948 180)
			(size 0.3048 0.3048)
			(layers "F.Cu" "F.Mask" "F.Paste")
			(net "GND")
		)
	)
)
